(kicad_pcb
	(version 20260206)
	(generator "pcbnew")
	(generator_version "10.0")
	(general
		(thickness 1.6)
		(legacy_teardrops no)
	)
	(paper "A4")
	(title_block
		(title "12092022_DA0F0TFB6D0_F0T_FAN_BOARD_MP5048_D_brd_v02_OCP.brd")
		(comment 1 "Grand Teton / footprints 859-859 of 924")
	)
	(layers
		(0 "F.Cu" signal "TOP")
		(4 "In1.Cu" signal "GND")
		(6 "In2.Cu" signal "IN1")
		(8 "In3.Cu" signal "IN2")
		(10 "In4.Cu" signal "GND1")
		(2 "B.Cu" signal "BOTTOM")
		(9 "F.Adhes" user "F.Adhesive")
		(11 "B.Adhes" user "B.Adhesive")
		(13 "F.Paste" user "Package Geometry/Pastemask Top")
		(15 "B.Paste" user "Package Geometry/Pastemask Bottom")
		(5 "F.SilkS" user "Ref Des/Silkscreen Top")
		(7 "B.SilkS" user "Ref Des/Silkscreen Bottom")
		(1 "F.Mask" user "Board Geometry/Soldermask Top")
		(3 "B.Mask" user "Board Geometry/Soldermask Bottom")
		(17 "Dwgs.User" user "User.Drawings")
		(19 "Cmts.User" user "User.Comments")
		(21 "Eco1.User" user "User.Eco1")
		(23 "Eco2.User" user "User.Eco2")
		(25 "Edge.Cuts" user "Board Geometry/Outline")
		(27 "Margin" user)
		(31 "F.CrtYd" user "Package Geometry/Place Bound Top")
		(29 "B.CrtYd" user "Package Geometry/Place Bound Bottom")
		(35 "F.Fab" user "Ref Des/Assembly Top")
		(33 "B.Fab" user "Ref Des/Assembly Bottom")
	)
	(footprint ""
		(layer "B.Cu")
		(at 42.01668 -264.404856 180)
		(property "Reference" "PU1"
			(at -5.86232 -2.430526 0)
			(unlocked yes)
			(layer "B.SilkS")
			(effects
				(font
					(size 0.7874 0.5842)
					(thickness 0.1524)
				)
				(justify left mirror)
			)
		)
		(property "Value" ""
			(at 0 0 0)
			(layer "B.Fab")
			(effects
				(font
					(size 1.27 1.27)
				)
				(justify mirror)
			)
		)
		(duplicate_pad_numbers_are_jumpers no)
		(fp_line
			(start 2.549906 2.549906)
			(end 2.4384 2.549906)
			(stroke
				(width 0.1524)
				(type default)
			)
			(layer "B.SilkS")
		)
		(fp_line
			(start 2.549906 2.2352)
			(end 2.549906 2.549906)
			(stroke
				(width 0.1524)
				(type default)
			)
			(layer "B.SilkS")
		)
		(fp_line
			(start 2.549906 1.4986)
			(end 2.549906 1.7526)
			(stroke
				(width 0.1524)
				(type default)
			)
			(layer "B.SilkS")
		)
		(fp_line
			(start 2.549906 0.6858)
			(end 2.549906 0.9144)
			(stroke
				(width 0.1524)
				(type default)
			)
			(layer "B.SilkS")
		)
		(fp_line
			(start 2.549906 -0.9144)
			(end 2.549906 0.1016)
			(stroke
				(width 0.1524)
				(type default)
			)
			(layer "B.SilkS")
		)
		(fp_line
			(start 2.549906 -1.7526)
			(end 2.549906 -1.4986)
			(stroke
				(width 0.1524)
				(type default)
			)
			(layer "B.SilkS")
		)
		(fp_line
			(start 2.549906 -2.549906)
			(end 2.549906 -2.2352)
			(stroke
				(width 0.1524)
				(type default)
			)
			(layer "B.SilkS")
		)
		(fp_line
			(start 2.4384 -2.549906)
			(end 2.549906 -2.549906)
			(stroke
				(width 0.1524)
				(type default)
			)
			(layer "B.SilkS")
		)
		(fp_line
			(start 2.199894 -3.9624)
			(end 2.199894 -2.9464)
			(stroke
				(width 0.1524)
				(type default)
			)
			(layer "B.SilkS")
		)
		(fp_line
			(start 0.199898 -3.4544)
			(end 0.199898 -2.9464)
			(stroke
				(width 0.1524)
				(type default)
			)
			(layer "B.SilkS")
		)
		(fp_line
			(start -0.199898 2.9464)
			(end -0.199898 3.9624)
			(stroke
				(width 0.1524)
				(type default)
			)
			(layer "B.SilkS")
		)
		(fp_line
			(start -1.800098 -3.9624)
			(end -1.800098 -2.9464)
			(stroke
				(width 0.1524)
				(type default)
			)
			(layer "B.SilkS")
		)
		(fp_line
			(start -2.199894 2.9464)
			(end -2.199894 3.4544)
			(stroke
				(width 0.1524)
				(type default)
			)
			(layer "B.SilkS")
		)
		(fp_line
			(start -2.4384 2.549906)
			(end -2.549906 2.549906)
			(stroke
				(width 0.1524)
				(type default)
			)
			(layer "B.SilkS")
		)
		(fp_line
			(start -2.549906 2.549906)
			(end -2.549906 2.2352)
			(stroke
				(width 0.1524)
				(type default)
			)
			(layer "B.SilkS")
		)
		(fp_line
			(start -2.549906 1.7526)
			(end -2.549906 1.4986)
			(stroke
				(width 0.1524)
				(type default)
			)
			(layer "B.SilkS")
		)
		(fp_line
			(start -2.549906 0.9144)
			(end -2.549906 -0.1016)
			(stroke
				(width 0.1524)
				(type default)
			)
			(layer "B.SilkS")
		)
		(fp_line
			(start -2.549906 -0.6858)
			(end -2.549906 -0.9144)
			(stroke
				(width 0.1524)
				(type default)
			)
			(layer "B.SilkS")
		)
		(fp_line
			(start -2.549906 -1.4986)
			(end -2.549906 -1.7526)
			(stroke
				(width 0.1524)
				(type default)
			)
			(layer "B.SilkS")
		)
		(fp_line
			(start -2.549906 -2.2352)
			(end -2.549906 -2.549906)
			(stroke
				(width 0.1524)
				(type default)
			)
			(layer "B.SilkS")
		)
		(fp_line
			(start -2.549906 -2.549906)
			(end -2.4384 -2.549906)
			(stroke
				(width 0.1524)
				(type default)
			)
			(layer "B.SilkS")
		)
		(fp_poly
			(pts
				(xy 3.53568 -1.498346) (xy 2.939034 -1.199896) (xy 3.53568 -0.9017)
			)
			(stroke
				(width 0)
				(type default)
			)
			(fill yes)
			(layer "B.SilkS")
		)
		(fp_line
			(start 2.549906 2.549906)
			(end -2.549906 2.549906)
			(stroke
				(width 0.1)
				(type default)
			)
			(layer "B.Fab")
		)
		(fp_line
			(start 2.549906 -2.549906)
			(end 2.549906 2.549906)
			(stroke
				(width 0.1)
				(type default)
			)
			(layer "B.Fab")
		)
		(fp_line
			(start 2.199894 -3.9624)
			(end 2.199894 -2.9464)
			(stroke
				(width 0.1)
				(type default)
			)
			(layer "B.Fab")
		)
		(fp_line
			(start 1.800098 2.9464)
			(end 1.800098 3.4544)
			(stroke
				(width 0.1)
				(type default)
			)
			(layer "B.Fab")
		)
		(fp_line
			(start 0.199898 -3.4544)
			(end 0.199898 -2.9464)
			(stroke
				(width 0.1)
				(type default)
			)
			(layer "B.Fab")
		)
		(fp_line
			(start -0.199898 2.9464)
			(end -0.199898 3.9624)
			(stroke
				(width 0.1)
				(type default)
			)
			(layer "B.Fab")
		)
		(fp_line
			(start -1.800098 -3.9624)
			(end -1.800098 -2.9464)
			(stroke
				(width 0.1)
				(type default)
			)
			(layer "B.Fab")
		)
		(fp_line
			(start -2.199894 2.9464)
			(end -2.199894 3.4544)
			(stroke
				(width 0.1)
				(type default)
			)
			(layer "B.Fab")
		)
		(fp_line
			(start -2.549906 2.549906)
			(end -2.549906 -2.549906)
			(stroke
				(width 0.1)
				(type default)
			)
			(layer "B.Fab")
		)
		(fp_line
			(start -2.549906 -2.549906)
			(end 2.549906 -2.549906)
			(stroke
				(width 0.1)
				(type default)
			)
			(layer "B.Fab")
		)
		(fp_poly
			(pts
				(xy 3.7084 -1.584706) (xy 2.939034 -1.199896) (xy 3.7084 -0.81534)
			)
			(stroke
				(width 0)
				(type default)
			)
			(fill yes)
			(layer "B.Fab")
		)
		(fp_text user "3"
			(at 3.37693 1.152144 270)
			(unlocked yes)
			(layer "B.SilkS")
			(effects
				(font
					(size 0.635 0.4064)
					(thickness 0.1524)
				)
				(justify mirror)
			)
		)
		(fp_text user "30"
			(at 2.90068 -3.134106 0)
			(unlocked yes)
			(layer "B.SilkS")
			(effects
				(font
					(size 0.635 0.4064)
					(thickness 0.1524)
				)
				(justify mirror)
			)
		)
		(fp_text user "4"
			(at 2.64668 3.088894 0)
			(unlocked yes)
			(layer "B.SilkS")
			(effects
				(font
					(size 0.635 0.4064)
					(thickness 0.1524)
				)
				(justify mirror)
			)
		)
		(fp_text user "15"
			(at -2.94132 3.088894 0)
			(unlocked yes)
			(layer "B.SilkS")
			(effects
				(font
					(size 0.635 0.4064)
					(thickness 0.1524)
				)
				(justify mirror)
			)
		)
		(fp_text user "19"
			(at -3.06832 -3.134106 0)
			(unlocked yes)
			(layer "B.SilkS")
			(effects
				(font
					(size 0.635 0.4064)
					(thickness 0.1524)
				)
				(justify mirror)
			)
		)
		(fp_text user "16"
			(at -3.35407 1.152144 270)
			(unlocked yes)
			(layer "B.SilkS")
			(effects
				(font
					(size 0.635 0.4064)
					(thickness 0.1524)
				)
				(justify mirror)
			)
		)
		(fp_text user "18"
			(at -3.35407 -1.260856 270)
			(unlocked yes)
			(layer "B.SilkS")
			(effects
				(font
					(size 0.635 0.4064)
					(thickness 0.1524)
				)
				(justify mirror)
			)
		)
		(fp_text user "3"
			(at 3.299968 1.1938 90)
			(unlocked yes)
			(layer "B.Fab")
			(effects
				(font
					(size 0.635 0.4064)
					(thickness 0.1524)
				)
				(justify mirror)
			)
		)
		(fp_text user "30"
			(at 2.9464 -3.045968 180)
			(unlocked yes)
			(layer "B.Fab")
			(effects
				(font
					(size 0.635 0.4064)
					(thickness 0.1524)
				)
				(justify mirror)
			)
		)
		(fp_text user "4"
			(at 2.6416 3.151632 180)
			(unlocked yes)
			(layer "B.Fab")
			(effects
				(font
					(size 0.635 0.4064)
					(thickness 0.1524)
				)
				(justify mirror)
			)
		)
		(fp_text user "19"
			(at -2.8448 -3.096768 180)
			(unlocked yes)
			(layer "B.Fab")
			(effects
				(font
					(size 0.635 0.4064)
					(thickness 0.1524)
				)
				(justify mirror)
			)
		)
		(fp_text user "15"
			(at -2.8956 3.126232 180)
			(unlocked yes)
			(layer "B.Fab")
			(effects
				(font
					(size 0.635 0.4064)
					(thickness 0.1524)
				)
				(justify mirror)
			)
		)
		(fp_text user "18"
			(at -3.304032 -1.2192 90)
			(unlocked yes)
			(layer "B.Fab")
			(effects
				(font
					(size 0.635 0.4064)
					(thickness 0.1524)
				)
				(justify mirror)
			)
		)
		(fp_text user "16"
			(at -3.329432 1.2192 90)
			(unlocked yes)
			(layer "B.Fab")
			(effects
				(font
					(size 0.635 0.4064)
					(thickness 0.1524)
				)
				(justify mirror)
			)
		)
		(pad "1" smd circle
			(at 1.599946 -1.199896 90)
			(size 0 0)
			(layers "B.Cu" "B.Mask" "B.Paste")
			(net "P52V_HSC")
		)
		(pad "2" smd rect
			(at 1.549908 0.40005 270)
			(size 0.3048 2.5146)
			(layers "B.Cu" "B.Mask" "B.Paste")
			(net "P52V_HSC")
		)
		(pad "3" smd rect
			(at 1.549908 1.199896 270)
			(size 0.3048 2.5146)
			(layers "B.Cu" "B.Mask" "B.Paste")
			(net "P52V_FAN_0")
		)
		(pad "4" smd circle
			(at 2.199894 2.350008 180)
			(size 0 0)
			(layers "B.Cu" "B.Mask" "B.Paste")
			(net "P52V_FAN_0")
		)
		(pad "5" smd rect
			(at 1.800098 2.350008)
			(size 0.1778 0.9144)
			(layers "B.Cu" "B.Mask" "B.Paste")
			(net "P52V_FAN_0")
		)
		(pad "6" smd rect
			(at 1.400048 2.350008)
			(size 0.1778 0.9144)
			(layers "B.Cu" "B.Mask" "B.Paste")
			(net "P52V_FAN_0")
		)
		(pad "7" smd rect
			(at 0.999998 2.350008)
			(size 0.1778 0.9144)
			(layers "B.Cu" "B.Mask" "B.Paste")
			(net "P52V_FAN_0")
		)
		(pad "8" smd rect
			(at 0.599948 2.350008)
			(size 0.1778 0.9144)
			(layers "B.Cu" "B.Mask" "B.Paste")
			(net "P52V_FAN_0")
		)
		(pad "9" smd rect
			(at 0.199898 2.350008)
			(size 0.1778 0.9144)
			(layers "B.Cu" "B.Mask" "B.Paste")
			(net "P52V_FAN_0")
		)
		(pad "10" smd rect
			(at -0.199898 2.350008)
			(size 0.1778 0.9144)
			(layers "B.Cu" "B.Mask" "B.Paste")
			(net "P52V_FAN_0")
		)
		(pad "11" smd rect
			(at -0.599948 2.350008)
			(size 0.1778 0.9144)
			(layers "B.Cu" "B.Mask" "B.Paste")
			(net "P52V_FAN_0")
		)
		(pad "12" smd rect
			(at -0.999998 2.350008)
			(size 0.1778 0.9144)
			(layers "B.Cu" "B.Mask" "B.Paste")
			(net "P52V_FAN_0")
		)
		(pad "13" smd rect
			(at -1.400048 2.350008)
			(size 0.1778 0.9144)
			(layers "B.Cu" "B.Mask" "B.Paste")
			(net "P52V_FAN_0")
		)
		(pad "14" smd rect
			(at -1.800098 2.350008)
			(size 0.1778 0.9144)
			(layers "B.Cu" "B.Mask" "B.Paste")
			(net "P52V_FAN_0")
		)
		(pad "15" smd circle
			(at -2.199894 2.350008 180)
			(size 0 0)
			(layers "B.Cu" "B.Mask" "B.Paste")
			(net "P52V_FAN_0")
		)
		(pad "16" smd rect
			(at -1.549908 1.199896 270)
			(size 0.3048 2.5146)
			(layers "B.Cu" "B.Mask" "B.Paste")
			(net "P52V_FAN_0")
		)
		(pad "17" smd rect
			(at -1.549908 -0.40005 270)
			(size 0.3048 2.5146)
			(layers "B.Cu" "B.Mask" "B.Paste")
			(net "P52V_FAN_0")
		)
		(pad "18" smd rect
			(at -1.549908 -1.199896 270)
			(size 0.3048 2.5146)
			(layers "B.Cu" "B.Mask" "B.Paste")
			(net "P52V_HSC")
		)
		(pad "19" smd circle
			(at -2.199894 -2.350008)
			(size 0 0)
			(layers "B.Cu" "B.Mask" "B.Paste")
			(net "FAN_0_CS")
		)
		(pad "20" smd rect
			(at -1.800098 -2.350008)
			(size 0.1778 0.9144)
			(layers "B.Cu" "B.Mask" "B.Paste")
			(net "FAN_0_IMON")
		)
		(pad "21" smd rect
			(at -1.400048 -2.350008)
			(size 0.1778 0.9144)
			(layers "B.Cu" "B.Mask" "B.Paste")
			(net "FAN_0_SS")
		)
		(pad "22" smd rect
			(at -0.999998 -2.350008)
			(size 0.1778 0.9144)
			(layers "B.Cu" "B.Mask" "B.Paste")
			(net "FAN_0_FAULT")
		)
		(pad "23" smd rect
			(at -0.599948 -2.350008)
			(size 0.1778 0.9144)
			(layers "B.Cu" "B.Mask" "B.Paste")
			(net "FAN_0_TIMER")
		)
		(pad "24" smd rect
			(at -0.199898 -2.350008)
			(size 0.1778 0.9144)
			(layers "B.Cu" "B.Mask" "B.Paste")
			(net "FAN_0_CLREF")
		)
		(pad "25" smd rect
			(at 0.199898 -2.350008)
			(size 0.1778 0.9144)
			(layers "B.Cu" "B.Mask" "B.Paste")
			(net "GND")
		)
		(pad "26" smd rect
			(at 0.599948 -2.350008)
			(size 0.1778 0.9144)
			(layers "B.Cu" "B.Mask" "B.Paste")
			(net "FAN_0_ON")
		)
		(pad "27" smd rect
			(at 0.999998 -2.350008)
			(size 0.1778 0.9144)
			(layers "B.Cu" "B.Mask" "B.Paste")
			(net "FAN_0_P3V_R")
		)
		(pad "28" smd rect
			(at 1.400048 -2.350008)
			(size 0.1778 0.9144)
			(layers "B.Cu" "B.Mask" "B.Paste")
			(net "FAN_0_P5V")
		)
		(pad "29" smd rect
			(at 1.800098 -2.350008)
			(size 0.1778 0.9144)
			(layers "B.Cu" "B.Mask" "B.Paste")
			(net "FAN_0_TEMP")
		)
		(pad "30" smd circle
			(at 2.199894 -2.350008)
			(size 0 0)
			(layers "B.Cu" "B.Mask" "B.Paste")
			(net "FAN_0_MODE")
		)
	)
)
